(kicad_pcb
	(version 20241229)
	(generator "pcbnew")
	(generator_version "9.0")
	(general
		(thickness 1.62)
		(legacy_teardrops no)
	)
	(paper "A3")
	(title_block
		(title "COM Express 7 Baseboard")
		(date "2025-02-04")
		(rev "1.1.2")
		(company "Antmicro Ltd")
		(comment 1 "www.antmicro.com")
		(comment 9 "footprint 244 of 802 (U43), pads 80-118 of 144")
	)
	(layers
		(0 "F.Cu" signal)
		(4 "In1.Cu" signal)
		(6 "In2.Cu" signal)
		(8 "In3.Cu" signal)
		(10 "In4.Cu" signal)
		(12 "In5.Cu" signal)
		(14 "In6.Cu" signal)
		(2 "B.Cu" signal)
		(9 "F.Adhes" user "F.Adhesive")
		(11 "B.Adhes" user "B.Adhesive")
		(13 "F.Paste" user)
		(15 "B.Paste" user)
		(5 "F.SilkS" user "F.Silkscreen")
		(7 "B.SilkS" user "B.Silkscreen")
		(1 "F.Mask" user)
		(3 "B.Mask" user)
		(17 "Dwgs.User" user "User.Drawings")
		(19 "Cmts.User" user "User.Comments")
		(21 "Eco1.User" user "User.Eco1")
		(23 "Eco2.User" user "User.Eco2")
		(25 "Edge.Cuts" user)
		(27 "Margin" user)
		(31 "F.CrtYd" user "F.Courtyard")
		(29 "B.CrtYd" user "B.Courtyard")
		(35 "F.Fab" user)
		(33 "B.Fab" user)
	)
	(footprint "antmicro-footprints:BGA-144_12x12_13.05x13.05mm_P1.0mm"
		(layer "F.Cu")
		(at 150.95 137.36 -90)
		(property "Reference" "U43"
			(at 7.9 4.65 180)
			(layer "F.SilkS")
			(effects
				(font
					(size 0.7 0.7)
					(thickness 0.15)
				)
				(justify right bottom)
			)
		)
		(property "Value" "TLK10232CTR"
			(at 0 7.525 90)
			(layer "F.Fab")
			(effects
				(font
					(size 0.7 0.7)
					(thickness 0.15)
				)
				(justify right bottom)
			)
		)
		(property "Datasheet" "https://www.ti.com/lit/ds/symlink/tlk10232.pdf?ts=1712150848075&ref_url=https%253A%252F%252Fwww.mouser.pl%252F"
			(at 0 0 270)
			(layer "F.Fab")
			(hide yes)
			(effects
				(font
					(size 1.27 1.27)
					(thickness 0.15)
				)
			)
		)
		(property "Author" "Antmicro"
			(at 13.59 288.31 0)
			(layer "F.Fab")
			(hide yes)
			(effects
				(font
					(size 1 1)
					(thickness 0.15)
				)
			)
		)
		(property "License" "Apache-2.0"
			(at 13.59 288.31 0)
			(layer "F.Fab")
			(hide yes)
			(effects
				(font
					(size 1 1)
					(thickness 0.15)
				)
			)
		)
		(property "MPN" "TLK10232CTR"
			(at 13.59 288.31 0)
			(layer "F.Fab")
			(hide yes)
			(effects
				(font
					(size 1 1)
					(thickness 0.15)
				)
			)
		)
		(property "Manufacturer" "Texas Instruments"
			(at 13.59 288.31 0)
			(layer "F.Fab")
			(hide yes)
			(effects
				(font
					(size 1 1)
					(thickness 0.15)
				)
			)
		)
		(sheetname "KR to SFI #1")
		(sheetfile "kr_sfi.kicad_sch")
		(attr smd)
		(pad "G8" smd circle
			(at 1.5 0.5 270)
			(size 0.5 0.5)
			(layers "F.Cu" "F.Mask" "F.Paste")
			(net 74 "+1V0")
			(pinfunction "DVDD")
			(pintype "passive")
			(solder_mask_margin 0.05)
			(teardrops
				(best_length_ratio 0.4)
				(max_length 1)
				(best_width_ratio 0.9)
				(max_width 2)
				(curved_edges yes)
				(filter_ratio 0.9)
				(enabled yes)
				(allow_two_segments yes)
				(prefer_zone_connections yes)
			)
		)
		(pad "G9" smd circle
			(at 2.5 0.5 270)
			(size 0.5 0.5)
			(layers "F.Cu" "F.Mask" "F.Paste")
			(net 656 "Net-(U43C-PRTAD1)")
			(pinfunction "PRTAD1")
			(pintype "input")
			(solder_mask_margin 0.05)
			(teardrops
				(best_length_ratio 0.4)
				(max_length 1)
				(best_width_ratio 0.9)
				(max_width 2)
				(curved_edges yes)
				(filter_ratio 0.9)
				(enabled yes)
				(allow_two_segments yes)
				(prefer_zone_connections yes)
			)
		)
		(pad "G10" smd circle
			(at 3.5 0.5 270)
			(size 0.5 0.5)
			(layers "F.Cu" "F.Mask" "F.Paste")
			(net 74 "+1V0")
			(pinfunction "VDDA_{LS/HS}")
			(pintype "passive")
			(solder_mask_margin 0.05)
			(teardrops
				(best_length_ratio 0.4)
				(max_length 1)
				(best_width_ratio 0.9)
				(max_width 2)
				(curved_edges yes)
				(filter_ratio 0.9)
				(enabled yes)
				(allow_two_segments yes)
				(prefer_zone_connections yes)
			)
		)
		(pad "G11" smd circle
			(at 4.5 0.5 270)
			(size 0.5 0.5)
			(layers "F.Cu" "F.Mask" "F.Paste")
			(net 1 "GND")
			(pinfunction "GND")
			(pintype "passive")
			(solder_mask_margin 0.05)
			(teardrops
				(best_length_ratio 0.4)
				(max_length 1)
				(best_width_ratio 0.9)
				(max_width 2)
				(curved_edges yes)
				(filter_ratio 0.9)
				(enabled yes)
				(allow_two_segments yes)
				(prefer_zone_connections yes)
			)
		)
		(pad "G12" smd circle
			(at 5.5 0.5 270)
			(size 0.5 0.5)
			(layers "F.Cu" "F.Mask" "F.Paste")
			(net 686 "/2xSFP+/KR to SFI #1/SFI_R.RX-")
			(pinfunction "HSRXB-")
			(pintype "input")
			(solder_mask_margin 0.05)
			(teardrops
				(best_length_ratio 0.4)
				(max_length 1)
				(best_width_ratio 0.9)
				(max_width 2)
				(curved_edges yes)
				(filter_ratio 0.9)
				(enabled yes)
				(allow_two_segments yes)
				(prefer_zone_connections yes)
			)
		)
		(pad "H1" smd circle
			(at -5.5 1.5 270)
			(size 0.5 0.5)
			(layers "F.Cu" "F.Mask" "F.Paste")
			(net 816 "unconnected-(U43B-INB0+-PadH1)")
			(pinfunction "INB0+")
			(pintype "input+no_connect")
			(solder_mask_margin 0.05)
			(teardrops
				(best_length_ratio 0.4)
				(max_length 1)
				(best_width_ratio 0.9)
				(max_width 2)
				(curved_edges yes)
				(filter_ratio 0.9)
				(enabled yes)
				(allow_two_segments yes)
				(prefer_zone_connections yes)
			)
		)
		(pad "H2" smd circle
			(at -4.5 1.5 270)
			(size 0.5 0.5)
			(layers "F.Cu" "F.Mask" "F.Paste")
			(net 1 "GND")
			(pinfunction "GND")
			(pintype "passive")
			(solder_mask_margin 0.05)
			(teardrops
				(best_length_ratio 0.4)
				(max_length 1)
				(best_width_ratio 0.9)
				(max_width 2)
				(curved_edges yes)
				(filter_ratio 0.9)
				(enabled yes)
				(allow_two_segments yes)
				(prefer_zone_connections yes)
			)
		)
		(pad "H3" smd circle
			(at -3.5 1.5 270)
			(size 0.5 0.5)
			(layers "F.Cu" "F.Mask" "F.Paste")
			(net 817 "unconnected-(U43B-OUTB0--PadH3)")
			(pinfunction "OUTB0-")
			(pintype "output+no_connect")
			(solder_mask_margin 0.05)
			(teardrops
				(best_length_ratio 0.4)
				(max_length 1)
				(best_width_ratio 0.9)
				(max_width 2)
				(curved_edges yes)
				(filter_ratio 0.9)
				(enabled yes)
				(allow_two_segments yes)
				(prefer_zone_connections yes)
			)
		)
		(pad "H4" smd circle
			(at -2.5 1.5 270)
			(size 0.5 0.5)
			(layers "F.Cu" "F.Mask" "F.Paste")
			(net 1 "GND")
			(pinfunction "GND")
			(pintype "passive")
			(solder_mask_margin 0.05)
			(teardrops
				(best_length_ratio 0.4)
				(max_length 1)
				(best_width_ratio 0.9)
				(max_width 2)
				(curved_edges yes)
				(filter_ratio 0.9)
				(enabled yes)
				(allow_two_segments yes)
				(prefer_zone_connections yes)
			)
		)
		(pad "H5" smd circle
			(at -1.5 1.5 270)
			(size 0.5 0.5)
			(layers "F.Cu" "F.Mask" "F.Paste")
			(net 141 "/2xSFP+/KR to SFI #1/~{RESET}")
			(pinfunction "~{RESET}")
			(pintype "input")
			(solder_mask_margin 0.05)
			(teardrops
				(best_length_ratio 0.4)
				(max_length 1)
				(best_width_ratio 0.9)
				(max_width 2)
				(curved_edges yes)
				(filter_ratio 0.9)
				(enabled yes)
				(allow_two_segments yes)
				(prefer_zone_connections yes)
			)
		)
		(pad "H6" smd circle
			(at -0.5 1.5 270)
			(size 0.5 0.5)
			(layers "F.Cu" "F.Mask" "F.Paste")
			(net 74 "+1V0")
			(pinfunction "VDDD")
			(pintype "passive")
			(solder_mask_margin 0.05)
			(teardrops
				(best_length_ratio 0.4)
				(max_length 1)
				(best_width_ratio 0.9)
				(max_width 2)
				(curved_edges yes)
				(filter_ratio 0.9)
				(enabled yes)
				(allow_two_segments yes)
				(prefer_zone_connections yes)
			)
		)
		(pad "H7" smd circle
			(at 0.5 1.5 270)
			(size 0.5 0.5)
			(layers "F.Cu" "F.Mask" "F.Paste")
			(net 74 "+1V0")
			(pinfunction "DVDD")
			(pintype "passive")
			(solder_mask_margin 0.05)
			(teardrops
				(best_length_ratio 0.4)
				(max_length 1)
				(best_width_ratio 0.9)
				(max_width 2)
				(curved_edges yes)
				(filter_ratio 0.9)
				(enabled yes)
				(allow_two_segments yes)
				(prefer_zone_connections yes)
			)
		)
		(pad "H8" smd circle
			(at 1.5 1.5 270)
			(size 0.5 0.5)
			(layers "F.Cu" "F.Mask" "F.Paste")
			(net 74 "+1V0")
			(pinfunction "VDDD")
			(pintype "passive")
			(solder_mask_margin 0.05)
			(teardrops
				(best_length_ratio 0.4)
				(max_length 1)
				(best_width_ratio 0.9)
				(max_width 2)
				(curved_edges yes)
				(filter_ratio 0.9)
				(enabled yes)
				(allow_two_segments yes)
				(prefer_zone_connections yes)
			)
		)
		(pad "H9" smd circle
			(at 2.5 1.5 270)
			(size 0.5 0.5)
			(layers "F.Cu" "F.Mask" "F.Paste")
			(net 739 "Net-(U43B-LS_OK_{OUT_B})")
			(pinfunction "LS_OK_{OUT_B}")
			(pintype "output")
			(solder_mask_margin 0.05)
			(teardrops
				(best_length_ratio 0.4)
				(max_length 1)
				(best_width_ratio 0.9)
				(max_width 2)
				(curved_edges yes)
				(filter_ratio 0.9)
				(enabled yes)
				(allow_two_segments yes)
				(prefer_zone_connections yes)
			)
		)
		(pad "H10" smd circle
			(at 3.5 1.5 270)
			(size 0.5 0.5)
			(layers "F.Cu" "F.Mask" "F.Paste")
			(net 662 "Net-(U43C-MODE_{SEL})")
			(pinfunction "MODE_{SEL}")
			(pintype "input")
			(solder_mask_margin 0.05)
			(teardrops
				(best_length_ratio 0.4)
				(max_length 1)
				(best_width_ratio 0.9)
				(max_width 2)
				(curved_edges yes)
				(filter_ratio 0.9)
				(enabled yes)
				(allow_two_segments yes)
				(prefer_zone_connections yes)
			)
		)
		(pad "H11" smd circle
			(at 4.5 1.5 270)
			(size 0.5 0.5)
			(layers "F.Cu" "F.Mask" "F.Paste")
			(net 1 "GND")
			(pinfunction "GND")
			(pintype "passive")
			(solder_mask_margin 0.05)
			(teardrops
				(best_length_ratio 0.4)
				(max_length 1)
				(best_width_ratio 0.9)
				(max_width 2)
				(curved_edges yes)
				(filter_ratio 0.9)
				(enabled yes)
				(allow_two_segments yes)
				(prefer_zone_connections yes)
			)
		)
		(pad "H12" smd circle
			(at 5.5 1.5 270)
			(size 0.5 0.5)
			(layers "F.Cu" "F.Mask" "F.Paste")
			(net 667 "/2xSFP+/KR to SFI #1/SFI_R.RX+")
			(pinfunction "HSRXB+")
			(pintype "input")
			(solder_mask_margin 0.05)
			(teardrops
				(best_length_ratio 0.4)
				(max_length 1)
				(best_width_ratio 0.9)
				(max_width 2)
				(curved_edges yes)
				(filter_ratio 0.9)
				(enabled yes)
				(allow_two_segments yes)
				(prefer_zone_connections yes)
			)
		)
		(pad "J1" smd circle
			(at -5.5 2.5 270)
			(size 0.5 0.5)
			(layers "F.Cu" "F.Mask" "F.Paste")
			(net 818 "unconnected-(U43B-INB0--PadJ1)")
			(pinfunction "INB0-")
			(pintype "input+no_connect")
			(solder_mask_margin 0.05)
			(teardrops
				(best_length_ratio 0.4)
				(max_length 1)
				(best_width_ratio 0.9)
				(max_width 2)
				(curved_edges yes)
				(filter_ratio 0.9)
				(enabled yes)
				(allow_two_segments yes)
				(prefer_zone_connections yes)
			)
		)
		(pad "J2" smd circle
			(at -4.5 2.5 270)
			(size 0.5 0.5)
			(layers "F.Cu" "F.Mask" "F.Paste")
			(net 74 "+1V0")
			(pinfunction "VDDA_{LS/HS}")
			(pintype "passive")
			(solder_mask_margin 0.05)
			(teardrops
				(best_length_ratio 0.4)
				(max_length 1)
				(best_width_ratio 0.9)
				(max_width 2)
				(curved_edges yes)
				(filter_ratio 0.9)
				(enabled yes)
				(allow_two_segments yes)
				(prefer_zone_connections yes)
			)
		)
		(pad "J3" smd circle
			(at -3.5 2.5 270)
			(size 0.5 0.5)
			(layers "F.Cu" "F.Mask" "F.Paste")
			(net 819 "unconnected-(U43B-OUTB0+-PadJ3)")
			(pinfunction "OUTB0+")
			(pintype "output+no_connect")
			(solder_mask_margin 0.05)
			(teardrops
				(best_length_ratio 0.4)
				(max_length 1)
				(best_width_ratio 0.9)
				(max_width 2)
				(curved_edges yes)
				(filter_ratio 0.9)
				(enabled yes)
				(allow_two_segments yes)
				(prefer_zone_connections yes)
			)
		)
		(pad "J4" smd circle
			(at -2.5 2.5 270)
			(size 0.5 0.5)
			(layers "F.Cu" "F.Mask" "F.Paste")
			(net 660 "Net-(U43B-~{PDTRXB})")
			(pinfunction "~{PDTRXB}")
			(pintype "input")
			(solder_mask_margin 0.05)
			(teardrops
				(best_length_ratio 0.4)
				(max_length 1)
				(best_width_ratio 0.9)
				(max_width 2)
				(curved_edges yes)
				(filter_ratio 0.9)
				(enabled yes)
				(allow_two_segments yes)
				(prefer_zone_connections yes)
			)
		)
		(pad "J5" smd circle
			(at -1.5 2.5 270)
			(size 0.5 0.5)
			(layers "F.Cu" "F.Mask" "F.Paste")
			(net 1 "GND")
			(pinfunction "GND")
			(pintype "passive")
			(solder_mask_margin 0.05)
			(teardrops
				(best_length_ratio 0.4)
				(max_length 1)
				(best_width_ratio 0.9)
				(max_width 2)
				(curved_edges yes)
				(filter_ratio 0.9)
				(enabled yes)
				(allow_two_segments yes)
				(prefer_zone_connections yes)
			)
		)
		(pad "J6" smd circle
			(at -0.5 2.5 270)
			(size 0.5 0.5)
			(layers "F.Cu" "F.Mask" "F.Paste")
			(net 659 "Net-(U43C-PRTAD3)")
			(pinfunction "PRTAD3")
			(pintype "input")
			(solder_mask_margin 0.05)
			(teardrops
				(best_length_ratio 0.4)
				(max_length 1)
				(best_width_ratio 0.9)
				(max_width 2)
				(curved_edges yes)
				(filter_ratio 0.9)
				(enabled yes)
				(allow_two_segments yes)
				(prefer_zone_connections yes)
			)
		)
		(pad "J7" smd circle
			(at 0.5 2.5 270)
			(size 0.5 0.5)
			(layers "F.Cu" "F.Mask" "F.Paste")
			(net 649 "/2xSFP+/KR to SFI #1/MDIO")
			(pinfunction "MDIO")
			(pintype "bidirectional")
			(solder_mask_margin 0.05)
			(teardrops
				(best_length_ratio 0.4)
				(max_length 1)
				(best_width_ratio 0.9)
				(max_width 2)
				(curved_edges yes)
				(filter_ratio 0.9)
				(enabled yes)
				(allow_two_segments yes)
				(prefer_zone_connections yes)
			)
		)
		(pad "J8" smd circle
			(at 1.5 2.5 270)
			(size 0.5 0.5)
			(layers "F.Cu" "F.Mask" "F.Paste")
			(net 651 "/2xSFP+/KR to SFI #1/MDC")
			(pinfunction "MDC")
			(pintype "input")
			(solder_mask_margin 0.05)
			(teardrops
				(best_length_ratio 0.4)
				(max_length 1)
				(best_width_ratio 0.9)
				(max_width 2)
				(curved_edges yes)
				(filter_ratio 0.9)
				(enabled yes)
				(allow_two_segments yes)
				(prefer_zone_connections yes)
			)
		)
		(pad "J9" smd circle
			(at 2.5 2.5 270)
			(size 0.5 0.5)
			(layers "F.Cu" "F.Mask" "F.Paste")
			(net 727 "Net-(U43C-PRBS_{PASS})")
			(pinfunction "PRBS_{PASS}")
			(pintype "output")
			(solder_mask_margin 0.05)
			(teardrops
				(best_length_ratio 0.4)
				(max_length 1)
				(best_width_ratio 0.9)
				(max_width 2)
				(curved_edges yes)
				(filter_ratio 0.9)
				(enabled yes)
				(allow_two_segments yes)
				(prefer_zone_connections yes)
			)
		)
		(pad "J10" smd circle
			(at 3.5 2.5 270)
			(size 0.5 0.5)
			(layers "F.Cu" "F.Mask" "F.Paste")
			(net 654 "Net-(U43C-GPI0)")
			(pinfunction "GPI0")
			(pintype "input")
			(solder_mask_margin 0.05)
			(teardrops
				(best_length_ratio 0.4)
				(max_length 1)
				(best_width_ratio 0.9)
				(max_width 2)
				(curved_edges yes)
				(filter_ratio 0.9)
				(enabled yes)
				(allow_two_segments yes)
				(prefer_zone_connections yes)
			)
		)
		(pad "J11" smd circle
			(at 4.5 2.5 270)
			(size 0.5 0.5)
			(layers "F.Cu" "F.Mask" "F.Paste")
			(net 78 "+1V8")
			(pinfunction "VDDRB_{LS/HS}")
			(pintype "power_in")
			(solder_mask_margin 0.05)
			(teardrops
				(best_length_ratio 0.4)
				(max_length 1)
				(best_width_ratio 0.9)
				(max_width 2)
				(curved_edges yes)
				(filter_ratio 0.9)
				(enabled yes)
				(allow_two_segments yes)
				(prefer_zone_connections yes)
			)
		)
		(pad "J12" smd circle
			(at 5.5 2.5 270)
			(size 0.5 0.5)
			(layers "F.Cu" "F.Mask" "F.Paste")
			(net 1 "GND")
			(pinfunction "GND")
			(pintype "passive")
			(solder_mask_margin 0.05)
			(teardrops
				(best_length_ratio 0.4)
				(max_length 1)
				(best_width_ratio 0.9)
				(max_width 2)
				(curved_edges yes)
				(filter_ratio 0.9)
				(enabled yes)
				(allow_two_segments yes)
				(prefer_zone_connections yes)
			)
		)
		(pad "K1" smd circle
			(at -5.5 3.5 270)
			(size 0.5 0.5)
			(layers "F.Cu" "F.Mask" "F.Paste")
			(net 1 "GND")
			(pinfunction "GND")
			(pintype "passive")
			(solder_mask_margin 0.05)
			(teardrops
				(best_length_ratio 0.4)
				(max_length 1)
				(best_width_ratio 0.9)
				(max_width 2)
				(curved_edges yes)
				(filter_ratio 0.9)
				(enabled yes)
				(allow_two_segments yes)
				(prefer_zone_connections yes)
			)
		)
		(pad "K2" smd circle
			(at -4.5 3.5 270)
			(size 0.5 0.5)
			(layers "F.Cu" "F.Mask" "F.Paste")
			(net 820 "unconnected-(U43B-INB1+-PadK2)")
			(pinfunction "INB1+")
			(pintype "input+no_connect")
			(solder_mask_margin 0.05)
			(teardrops
				(best_length_ratio 0.4)
				(max_length 1)
				(best_width_ratio 0.9)
				(max_width 2)
				(curved_edges yes)
				(filter_ratio 0.9)
				(enabled yes)
				(allow_two_segments yes)
				(prefer_zone_connections yes)
			)
		)
		(pad "K3" smd circle
			(at -3.5 3.5 270)
			(size 0.5 0.5)
			(layers "F.Cu" "F.Mask" "F.Paste")
			(net 78 "+1V8")
			(pinfunction "VDDRB_{LS/HS}")
			(pintype "passive")
			(solder_mask_margin 0.05)
			(teardrops
				(best_length_ratio 0.4)
				(max_length 1)
				(best_width_ratio 0.9)
				(max_width 2)
				(curved_edges yes)
				(filter_ratio 0.9)
				(enabled yes)
				(allow_two_segments yes)
				(prefer_zone_connections yes)
			)
		)
		(pad "K4" smd circle
			(at -2.5 3.5 270)
			(size 0.5 0.5)
			(layers "F.Cu" "F.Mask" "F.Paste")
			(net 821 "unconnected-(U43B-OUTB1--PadK4)")
			(pinfunction "OUTB1-")
			(pintype "output+no_connect")
			(solder_mask_margin 0.05)
			(teardrops
				(best_length_ratio 0.4)
				(max_length 1)
				(best_width_ratio 0.9)
				(max_width 2)
				(curved_edges yes)
				(filter_ratio 0.9)
				(enabled yes)
				(allow_two_segments yes)
				(prefer_zone_connections yes)
			)
		)
		(pad "K5" smd circle
			(at -1.5 3.5 270)
			(size 0.5 0.5)
			(layers "F.Cu" "F.Mask" "F.Paste")
			(net 822 "unconnected-(U43B-OUTB1+-PadK5)")
			(pinfunction "OUTB1+")
			(pintype "output+no_connect")
			(solder_mask_margin 0.05)
			(teardrops
				(best_length_ratio 0.4)
				(max_length 1)
				(best_width_ratio 0.9)
				(max_width 2)
				(curved_edges yes)
				(filter_ratio 0.9)
				(enabled yes)
				(allow_two_segments yes)
				(prefer_zone_connections yes)
			)
		)
		(pad "K6" smd circle
			(at -0.5 3.5 270)
			(size 0.5 0.5)
			(layers "F.Cu" "F.Mask" "F.Paste")
			(net 1 "GND")
			(pinfunction "GND")
			(pintype "passive")
			(solder_mask_margin 0.05)
			(teardrops
				(best_length_ratio 0.4)
				(max_length 1)
				(best_width_ratio 0.9)
				(max_width 2)
				(curved_edges yes)
				(filter_ratio 0.9)
				(enabled yes)
				(allow_two_segments yes)
				(prefer_zone_connections yes)
			)
		)
		(pad "K7" smd circle
			(at 0.5 3.5 270)
			(size 0.5 0.5)
			(layers "F.Cu" "F.Mask" "F.Paste")
			(net 74 "+1V0")
			(pinfunction "VDDO1")
			(pintype "power_in")
			(solder_mask_margin 0.05)
			(teardrops
				(best_length_ratio 0.4)
				(max_length 1)
				(best_width_ratio 0.9)
				(max_width 2)
				(curved_edges yes)
				(filter_ratio 0.9)
				(enabled yes)
				(allow_two_segments yes)
				(prefer_zone_connections yes)
			)
		)
		(pad "K8" smd circle
			(at 1.5 3.5 270)
			(size 0.5 0.5)
			(layers "F.Cu" "F.Mask" "F.Paste")
			(net 737 "Net-(U43B-LOSB)")
			(pinfunction "LOSB")
			(pintype "output")
			(solder_mask_margin 0.05)
			(teardrops
				(best_length_ratio 0.4)
				(max_length 1)
				(best_width_ratio 0.9)
				(max_width 2)
				(curved_edges yes)
				(filter_ratio 0.9)
				(enabled yes)
				(allow_two_segments yes)
				(prefer_zone_connections yes)
			)
		)
		(pad "K9" smd circle
			(at 2.5 3.5 270)
			(size 0.5 0.5)
			(layers "F.Cu" "F.Mask" "F.Paste")
			(net 720 "Net-(U43C-REFCLK1+)")
			(pinfunction "REFCLK1+")
			(pintype "input")
			(solder_mask_margin 0.05)
			(teardrops
				(best_length_ratio 0.4)
				(max_length 1)
				(best_width_ratio 0.9)
				(max_width 2)
				(curved_edges yes)
				(filter_ratio 0.9)
				(enabled yes)
				(allow_two_segments yes)
				(prefer_zone_connections yes)
			)
		)
		(pad "K10" smd circle
			(at 3.5 3.5 270)
			(size 0.5 0.5)
			(layers "F.Cu" "F.Mask" "F.Paste")
			(net 721 "Net-(U43C-REFCLK1-)")
			(pinfunction "REFCLK1-")
			(pintype "input")
			(solder_mask_margin 0.05)
			(teardrops
				(best_length_ratio 0.4)
				(max_length 1)
				(best_width_ratio 0.9)
				(max_width 2)
				(curved_edges yes)
				(filter_ratio 0.9)
				(enabled yes)
				(allow_two_segments yes)
				(prefer_zone_connections yes)
			)
		)
	)
)
